# S9S_MB_2U (Grand Teton) — schematic netlist excerpt (pin names and nets, part order shuffled) for the footprints in the layout excerpt that follows; sources: Cadence DE-HDL packaged netlist, KiCad conversion of 03242023_DA0F0TMBIJ0_F0T_Motherboard_J_brd_V01_OCP.brd

PU27_P1_4  ISL99390FRZTR5935  ISL99390FRZ-TR5935 IC  pkg QFN21_6X5XB  page 286
  VOS  = PVCCIN_CPU1_VOS4
  AGND  = GND
  VCC  = PVCCIN_CPU1_VDD4
  PVCC  = PVCCIN_CPU1_PVCC
  PGND1  = GND
  GL1  = NC
  PGND2  = GND
  SW  = SW_PVCCIN_CPU1_SW4
  VIN1  = SW_P12V_PVCCIN_CPU1_FLT
  VIN2  = SW_P12V_PVCCIN_CPU1_FLT
  DNC  = NC
  PHASE  = SW_PVCCIN_CPU1_BOOTR4
  BOOT  = SW_PVCCIN_CPU1_BOOT4
  PWM  = PVCCIN_CPU1_PWM4
  EN  = PVCCIN_CPU1_VDD4
  TOUT_FLT  = PVCCIN_CPU1_ATSEN
  LSET  = PVCCIN_CPU1_LSET4
  IOUT  = PVCCIN_CPU1_IMON4
  REFIN  = PVCCIN_CPU1_VREF
  PGND3  = GND
  GL2  = NC

(kicad_pcb
	(version 20260206)
	(generator "pcbnew")
	(generator_version "10.0")
	(general
		(thickness 1.6)
		(legacy_teardrops no)
	)
	(paper "A4")
	(title_block
		(title "03242023_DA0F0TMBIJ0_F0T_Motherboard_J_brd_V01_OCP.brd")
		(comment 1 "Grand Teton / footprints 2236-2236 of 6105")
	)
	(layers
		(0 "F.Cu" signal "TOP")
		(4 "In1.Cu" signal "GND")
		(6 "In2.Cu" signal "IN1")
		(8 "In3.Cu" signal "GND1")
		(10 "In4.Cu" signal "IN2")
		(12 "In5.Cu" signal "GND2")
		(14 "In6.Cu" signal "IN3")
		(16 "In7.Cu" signal "GND3")
		(18 "In8.Cu" signal "VCC")
		(20 "In9.Cu" signal "VCC1")
		(22 "In10.Cu" signal "GND4")
		(24 "In11.Cu" signal "IN4")
		(26 "In12.Cu" signal "GND5")
		(28 "In13.Cu" signal "IN5")
		(30 "In14.Cu" signal "GND6")
		(32 "In15.Cu" signal "IN6")
		(34 "In16.Cu" signal "GND7")
		(2 "B.Cu" signal "BOTTOM")
		(9 "F.Adhes" user "F.Adhesive")
		(11 "B.Adhes" user "B.Adhesive")
		(13 "F.Paste" user "Package Geometry/Pastemask Top")
		(15 "B.Paste" user "Package Geometry/Pastemask Bottom")
		(5 "F.SilkS" user "Ref Des/Silkscreen Top")
		(7 "B.SilkS" user "Ref Des/Silkscreen Bottom")
		(1 "F.Mask" user "Board Geometry/Soldermask Top")
		(3 "B.Mask" user "Board Geometry/Soldermask Bottom")
		(17 "Dwgs.User" user "User.Drawings")
		(19 "Cmts.User" user "User.Comments")
		(21 "Eco1.User" user "User.Eco1")
		(23 "Eco2.User" user "User.Eco2")
		(25 "Edge.Cuts" user "Board Geometry/Outline")
		(27 "Margin" user)
		(31 "F.CrtYd" user "Package Geometry/Place Bound Top")
		(29 "B.CrtYd" user "Package Geometry/Place Bound Bottom")
		(35 "F.Fab" user "Ref Des/Assembly Top")
		(33 "B.Fab" user "Ref Des/Assembly Bottom")
	)
	(footprint ""
		(layer "F.Cu")
		(at 121.47931 -333.716122)
		(property "Reference" "PU27_P1_4"
			(at 3.92049 -12.962636 0)
			(unlocked yes)
			(layer "F.SilkS")
			(effects
				(font
					(size 0.7874 0.5842)
					(thickness 0.1524)
				)
				(justify left)
			)
		)
		(property "Value" ""
			(at 0 0 0)
			(layer "F.Fab")
			(effects
				(font
					(size 1.27 1.27)
				)
			)
		)
		(duplicate_pad_numbers_are_jumpers no)
		(fp_line
			(start -2.500122 -2.999994)
			(end -2.24409 -2.999994)
			(stroke
				(width 0.1524)
				(type default)
			)
			(layer "F.SilkS")
		)
		(fp_line
			(start -2.500122 -2.529078)
			(end -2.500122 -2.999994)
			(stroke
				(width 0.1524)
				(type default)
			)
			(layer "F.SilkS")
		)
		(fp_line
			(start -2.500122 0.6604)
			(end -2.500122 0.229108)
			(stroke
				(width 0.1524)
				(type default)
			)
			(layer "F.SilkS")
		)
		(fp_line
			(start -2.500122 2.999994)
			(end -2.500122 2.339594)
			(stroke
				(width 0.1524)
				(type default)
			)
			(layer "F.SilkS")
		)
		(fp_line
			(start -2.2987 2.999994)
			(end -2.500122 2.999994)
			(stroke
				(width 0.1524)
				(type default)
			)
			(layer "F.SilkS")
		)
		(fp_line
			(start 2.31394 -2.999994)
			(end 2.500122 -2.999994)
			(stroke
				(width 0.1524)
				(type default)
			)
			(layer "F.SilkS")
		)
		(fp_line
			(start 2.500122 -2.999994)
			(end 2.500122 -2.44348)
			(stroke
				(width 0.1524)
				(type default)
			)
			(layer "F.SilkS")
		)
		(fp_line
			(start 2.500122 2.339594)
			(end 2.500122 2.999994)
			(stroke
				(width 0.1524)
				(type default)
			)
			(layer "F.SilkS")
		)
		(fp_line
			(start 2.500122 2.999994)
			(end 2.2987 2.999994)
			(stroke
				(width 0.1524)
				(type default)
			)
			(layer "F.SilkS")
		)
		(fp_poly
			(pts
				(xy -2.226818 -3.642868) (xy -2.734818 -2.626868) (xy -3.242818 -3.642868)
			)
			(stroke
				(width 0)
				(type default)
			)
			(fill yes)
			(layer "F.SilkS")
		)
		(fp_line
			(start -2.500122 -2.999994)
			(end 2.500122 -2.999994)
			(stroke
				(width 0.1)
				(type default)
			)
			(layer "F.Fab")
		)
		(fp_line
			(start -2.500122 2.999994)
			(end -2.500122 -2.999994)
			(stroke
				(width 0.1)
				(type default)
			)
			(layer "F.Fab")
		)
		(fp_line
			(start 2.500122 -2.999994)
			(end 2.500122 2.999994)
			(stroke
				(width 0.1)
				(type default)
			)
			(layer "F.Fab")
		)
		(fp_line
			(start 2.500122 2.999994)
			(end -2.500122 2.999994)
			(stroke
				(width 0.1)
				(type default)
			)
			(layer "F.Fab")
		)
		(fp_poly
			(pts
				(xy -4.218432 -2.783078) (xy -4.218432 -1.767078) (xy -3.202432 -2.275078)
			)
			(stroke
				(width 0)
				(type default)
			)
			(fill yes)
			(layer "F.Fab")
		)
		(pad "1" smd rect
			(at -2.400046 -2.275078 90)
			(size 0.2286 0.6096)
			(layers "F.Cu" "F.Mask" "F.Paste")
			(net "PVCCIN_CPU1_VOS4")
		)
		(pad "2" smd rect
			(at -2.400046 -1.82499 90)
			(size 0.2286 0.6096)
			(layers "F.Cu" "F.Mask" "F.Paste")
			(net "GND")
		)
		(pad "3" smd rect
			(at -2.400046 -1.374902 90)
			(size 0.2286 0.6096)
			(layers "F.Cu" "F.Mask" "F.Paste")
			(net "PVCCIN_CPU1_VDD4")
		)
		(pad "4" smd rect
			(at -2.400046 -0.925068 90)
			(size 0.2286 0.6096)
			(layers "F.Cu" "F.Mask" "F.Paste")
			(net "PVCCIN_CPU1_PVCC")
		)
		(pad "5" smd rect
			(at -2.400046 -0.47498 90)
			(size 0.2286 0.6096)
			(layers "F.Cu" "F.Mask" "F.Paste")
			(net "GND")
		)
		(pad "6" smd rect
			(at -2.400046 -0.024892 90)
			(size 0.2286 0.6096)
			(layers "F.Cu" "F.Mask" "F.Paste")
			(net "Net_8529")
		)
		(pad "7_9-20_24" smd circle
			(at 0 1.150112 90)
			(size 0 0)
			(layers "F.Cu" "F.Mask" "F.Paste")
			(net "GND")
		)
		(pad "10_19" smd rect
			(at 0 2.899918 90)
			(size 0.6096 4.318)
			(layers "F.Cu" "F.Mask" "F.Paste")
			(net "SW_PVCCIN_CPU1_SW4")
		)
		(pad "25_29" smd rect
			(at 1.549908 -1.279906 270)
			(size 2.0574 2.3114)
			(layers "F.Cu" "F.Mask" "F.Paste")
			(net "SW_P12V_PVCCIN_CPU1_FLT")
		)
		(pad "30" smd rect
			(at 2.05994 -2.899918)
			(size 0.2286 0.6096)
			(layers "F.Cu" "F.Mask" "F.Paste")
			(net "SW_P12V_PVCCIN_CPU1_FLT")
		)
		(pad "31" smd rect
			(at 1.610106 -2.899918)
			(size 0.2286 0.6096)
			(layers "F.Cu" "F.Mask" "F.Paste")
			(net "Net_8530")
		)
		(pad "32" smd rect
			(at 1.160018 -2.899918)
			(size 0.2286 0.6096)
			(layers "F.Cu" "F.Mask" "F.Paste")
			(net "SW_PVCCIN_CPU1_BOOTR4")
		)
		(pad "33" smd rect
			(at 0.70993 -2.899918)
			(size 0.2286 0.6096)
			(layers "F.Cu" "F.Mask" "F.Paste")
			(net "SW_PVCCIN_CPU1_BOOT4")
		)
		(pad "34" smd rect
			(at 0.260096 -2.899918)
			(size 0.2286 0.6096)
			(layers "F.Cu" "F.Mask" "F.Paste")
			(net "PVCCIN_CPU1_PWM4")
		)
		(pad "35" smd rect
			(at -0.189992 -2.899918)
			(size 0.2286 0.6096)
			(layers "F.Cu" "F.Mask" "F.Paste")
			(net "PVCCIN_CPU1_VDD4")
		)
		(pad "36" smd rect
			(at -0.64008 -2.899918)
			(size 0.2286 0.6096)
			(layers "F.Cu" "F.Mask" "F.Paste")
			(net "PVCCIN_CPU1_ATSEN")
		)
		(pad "37" smd rect
			(at -1.089914 -2.899918)
			(size 0.2286 0.6096)
			(layers "F.Cu" "F.Mask" "F.Paste")
			(net "PVCCIN_CPU1_LSET4")
		)
		(pad "38" smd rect
			(at -1.540002 -2.899918)
			(size 0.2286 0.6096)
			(layers "F.Cu" "F.Mask" "F.Paste")
			(net "PVCCIN_CPU1_IMON4")
		)
		(pad "39" smd rect
			(at -1.99009 -2.899918)
			(size 0.2286 0.6096)
			(layers "F.Cu" "F.Mask" "F.Paste")
			(net "PVCCIN_CPU1_VREF")
		)
		(pad "40" smd rect
			(at -0.87503 -1.27508)
			(size 1.7526 1.9558)
			(layers "F.Cu" "F.Mask" "F.Paste")
			(net "GND")
		)
		(pad "41" smd rect
			(at -1.525016 0.249936 270)
			(size 0.3048 0.4572)
			(layers "F.Cu" "F.Mask" "F.Paste")
			(net "Net_8528")
		)
		(zone
			(layer "F.Cu")
			(hatch none 0.5)
			(connect_pads
				(clearance 0)
			)
			(min_thickness 0.25)
			(keepout
				(tracks not_allowed)
				(vias allowed)
				(pads allowed)
				(copperpour not_allowed)
				(footprints allowed)
			)
			(placement
				(enabled no)
				(sheetname "")
			)
			(fill
				(thermal_gap 0.5)
				(thermal_bridge_width 0.5)
				(island_removal_mode 0)
			)
			(polygon
				(pts
					(xy 118.979188 -330.716128) (xy 118.979188 -331.465428) (xy 123.979432 -331.465428) (xy 123.979432 -330.716128)
					(xy 123.68911 -330.716128) (xy 123.68911 -331.171804) (xy 119.26951 -331.171804) (xy 119.26951 -330.716128)
				)
			)
		)
		(zone
			(layer "F.Cu")
			(hatch none 0.5)
			(connect_pads
				(clearance 0)
			)
			(min_thickness 0.25)
			(keepout
				(tracks not_allowed)
				(vias allowed)
				(pads allowed)
				(copperpour not_allowed)
				(footprints allowed)
			)
			(placement
				(enabled no)
				(sheetname "")
			)
			(fill
				(thermal_gap 0.5)
				(thermal_bridge_width 0.5)
				(island_removal_mode 0)
			)
			(polygon
				(pts
					(xy 119.434864 -334.020668) (xy 119.67718 -334.020668) (xy 119.67718 -333.962502) (xy 120.46458 -333.962502)
					(xy 120.46458 -333.619348) (xy 120.528588 -333.619348) (xy 120.528588 -332.966822) (xy 118.979188 -332.966822)
					(xy 118.979188 -333.423514) (xy 119.674894 -333.423514) (xy 119.674894 -333.262986) (xy 120.233694 -333.262986)
					(xy 120.233694 -333.669386) (xy 119.674894 -333.669386) (xy 119.674894 -333.448914) (xy 118.979188 -333.448914)
					(xy 118.979188 -333.575914) (xy 119.434864 -333.575914)
				)
			)
		)
	)
)
